# TIMECARD (Time Appliance Project (Time Card)) — schematic netlist excerpt (pin names and nets, part order shuffled) for the footprints in the layout excerpt that follows; sources: Cadence DE-HDL packaged netlist, KiCad conversion of R4006-B0001-02_R01.brd

C245  CAPACITOR  0.1UF 25V 10%  pkg SMC_0402R_H022  page 15 : \1\ = XP3R3V ; \2\ = SG
R165  RESISTOR  10KOHM 1%  pkg SMC_0402R_H016  page 30 : \1\ = XP1R2V_EN_R ; \2\ = SG

(kicad_pcb
	(version 20260206)
	(generator "pcbnew")
	(generator_version "10.0")
	(general
		(thickness 1.6)
		(legacy_teardrops no)
	)
	(paper "A4")
	(title_block
		(title "timecard-production-celestica-r4006 — R4006-B0001-02_R01.brd")
		(comment 1 "Time Appliance Project (Time Card) / footprints 1003-1004 of 1113")
	)
	(layers
		(0 "F.Cu" signal "TOP")
		(4 "In1.Cu" signal "L02_GND1")
		(6 "In2.Cu" signal "L03_SIG1")
		(8 "In3.Cu" signal "L04_GND2")
		(10 "In4.Cu" signal "L05_VCC1")
		(12 "In5.Cu" signal "L06_VCC2")
		(14 "In6.Cu" signal "L07_GND3")
		(16 "In7.Cu" signal "L08_SIG2")
		(18 "In8.Cu" signal "L09_GND4")
		(2 "B.Cu" signal "BOTTOM")
		(9 "F.Adhes" user "F.Adhesive")
		(11 "B.Adhes" user "B.Adhesive")
		(13 "F.Paste" user "Package Geometry/Pastemask Top")
		(15 "B.Paste" user "Package Geometry/Pastemask Bottom")
		(5 "F.SilkS" user "Ref Des/Silkscreen Top")
		(7 "B.SilkS" user "Ref Des/Silkscreen Bottom")
		(1 "F.Mask" user "Board Geometry/Soldermask Top")
		(3 "B.Mask" user "Board Geometry/Soldermask Bottom")
		(17 "Dwgs.User" user "User.Drawings")
		(19 "Cmts.User" user "User.Comments")
		(21 "Eco1.User" user "User.Eco1")
		(23 "Eco2.User" user "User.Eco2")
		(25 "Edge.Cuts" user "Board Geometry/Outline")
		(27 "Margin" user)
		(31 "F.CrtYd" user "Package Geometry/Place Bound Top")
		(29 "B.CrtYd" user "Package Geometry/Place Bound Bottom")
		(35 "F.Fab" user "Ref Des/Assembly Top")
		(33 "B.Fab" user "Ref Des/Assembly Bottom")
	)
	(footprint ""
		(layer "B.Cu")
		(at 99.3648 -78.5368 180)
		(property "Reference" "R165"
			(at -0.5842 -2.37617 0)
			(unlocked yes)
			(layer "B.SilkS")
			(effects
				(font
					(size 0.7874 0.5842)
					(thickness 0.1524)
				)
				(justify mirror)
			)
		)
		(property "Value" "VAL*"
			(at -0.02032 2.13233 180)
			(unlocked yes)
			(layer "B.Fab")
			(hide yes)
			(effects
				(font
					(size 0.7874 0.5842)
					(thickness 0.1524)
				)
				(justify mirror)
			)
		)
		(property "Tolerance" "TOL*"
			(at -0.044704 3.05435 180)
			(unlocked yes)
			(layer "Cmts.User")
			(hide yes)
			(effects
				(font
					(size 0.7874 0.5842)
					(thickness 0.1524)
				)
				(justify mirror)
			)
		)
		(property "User Part Number" "PARTNUM*"
			(at -0.02032 4.024884 180)
			(unlocked yes)
			(layer "Cmts.User")
			(hide yes)
			(effects
				(font
					(size 0.7874 0.5842)
					(thickness 0.1524)
				)
				(justify mirror)
			)
		)
		(property "Device Type" "RESISTOR-G155-11002-01,10KOHM,A"
			(at -0.008382 1.210564 180)
			(unlocked yes)
			(layer "B.Fab")
			(hide yes)
			(effects
				(font
					(size 0.7874 0.5842)
					(thickness 0.1524)
				)
				(justify mirror)
			)
		)
		(duplicate_pad_numbers_are_jumpers no)
		(fp_line
			(start 1.143 0.5588)
			(end -1.143 0.5588)
			(stroke
				(width 0.1)
				(type default)
			)
			(layer "B.SilkS")
		)
		(fp_line
			(start 1.143 -0.5588)
			(end 1.143 0.5588)
			(stroke
				(width 0.1)
				(type default)
			)
			(layer "B.SilkS")
		)
		(fp_line
			(start -1.143 0.5588)
			(end -1.143 -0.5588)
			(stroke
				(width 0.1)
				(type default)
			)
			(layer "B.SilkS")
		)
		(fp_line
			(start -1.143 -0.5588)
			(end 1.143 -0.5588)
			(stroke
				(width 0.1)
				(type default)
			)
			(layer "B.SilkS")
		)
		(fp_rect
			(start 1.143 0.5588)
			(end -1.143 -0.5588)
			(stroke
				(width 0)
				(type default)
			)
			(fill no)
			(layer "B.CrtYd")
		)
		(fp_line
			(start 0.508 0.3048)
			(end -0.508 0.3048)
			(stroke
				(width 0.1)
				(type default)
			)
			(layer "B.Fab")
		)
		(fp_line
			(start 0.508 -0.3048)
			(end 0.508 0.3048)
			(stroke
				(width 0.1)
				(type default)
			)
			(layer "B.Fab")
		)
		(fp_line
			(start -0.508 0.3048)
			(end -0.508 -0.3048)
			(stroke
				(width 0.1)
				(type default)
			)
			(layer "B.Fab")
		)
		(fp_line
			(start -0.508 -0.3048)
			(end 0.508 -0.3048)
			(stroke
				(width 0.1)
				(type default)
			)
			(layer "B.Fab")
		)
		(pad "1" smd rect
			(at 0.5334 0)
			(size 0.7112 0.6096)
			(layers "B.Cu" "B.Mask" "B.Paste")
			(net "XP1R2V_EN_R")
		)
		(pad "2" smd rect
			(at -0.5334 0)
			(size 0.7112 0.6096)
			(layers "B.Cu" "B.Mask" "B.Paste")
			(net "SG")
		)
		(zone
			(layer "B.Cu")
			(hatch none 0.5)
			(connect_pads
				(clearance 0)
			)
			(min_thickness 0.25)
			(keepout
				(tracks allowed)
				(vias not_allowed)
				(pads allowed)
				(copperpour not_allowed)
				(footprints allowed)
			)
			(placement
				(enabled no)
				(sheetname "")
			)
			(fill
				(thermal_gap 0.5)
				(thermal_bridge_width 0.5)
				(island_removal_mode 0)
			)
			(polygon
				(pts
					(xy 99.2886 -78.8416) (xy 99.2886 -78.232) (xy 99.441 -78.232) (xy 99.441 -78.8416)
				)
			)
		)
	)
	(footprint ""
		(layer "B.Cu")
		(at 95.758 -20.066 90)
		(property "Reference" "C245"
			(at -0.381 2.11963 270)
			(unlocked yes)
			(layer "B.SilkS")
			(effects
				(font
					(size 0.7874 0.5842)
					(thickness 0.1524)
				)
				(justify mirror)
			)
		)
		(property "Value" "VAL*"
			(at -0.0762 2.067306 90)
			(unlocked yes)
			(layer "B.Fab")
			(hide yes)
			(effects
				(font
					(size 0.7874 0.5842)
					(thickness 0.1524)
				)
				(justify mirror)
			)
		)
		(property "Device Type" "CAPACITOR-G105-0B104-EK,0.1UF,A"
			(at -0.0508 1.127506 90)
			(unlocked yes)
			(layer "B.Fab")
			(hide yes)
			(effects
				(font
					(size 0.7874 0.5842)
					(thickness 0.1524)
				)
				(justify mirror)
			)
		)
		(property "User Part Number" "PARTNUM*"
			(at -0.1016 4.023106 90)
			(unlocked yes)
			(layer "Cmts.User")
			(hide yes)
			(effects
				(font
					(size 0.7874 0.5842)
					(thickness 0.1524)
				)
				(justify mirror)
			)
		)
		(property "Tolerance" "TOL*"
			(at -0.0762 3.032506 90)
			(unlocked yes)
			(layer "Cmts.User")
			(hide yes)
			(effects
				(font
					(size 0.7874 0.5842)
					(thickness 0.1524)
				)
				(justify mirror)
			)
		)
		(duplicate_pad_numbers_are_jumpers no)
		(fp_line
			(start 1.143 -0.5588)
			(end 1.143 0.5588)
			(stroke
				(width 0.1)
				(type default)
			)
			(layer "B.SilkS")
		)
		(fp_line
			(start -1.143 -0.5588)
			(end 1.143 -0.5588)
			(stroke
				(width 0.1)
				(type default)
			)
			(layer "B.SilkS")
		)
		(fp_line
			(start 1.143 0.5588)
			(end -1.143 0.5588)
			(stroke
				(width 0.1)
				(type default)
			)
			(layer "B.SilkS")
		)
		(fp_line
			(start -1.143 0.5588)
			(end -1.143 -0.5588)
			(stroke
				(width 0.1)
				(type default)
			)
			(layer "B.SilkS")
		)
		(fp_rect
			(start -1.143 -0.5588)
			(end 1.143 0.5588)
			(stroke
				(width 0)
				(type default)
			)
			(fill no)
			(layer "B.CrtYd")
		)
		(fp_line
			(start 0.508 -0.3048)
			(end 0.508 0.3048)
			(stroke
				(width 0.1)
				(type default)
			)
			(layer "B.Fab")
		)
		(fp_line
			(start -0.508 -0.3048)
			(end 0.508 -0.3048)
			(stroke
				(width 0.1)
				(type default)
			)
			(layer "B.Fab")
		)
		(fp_line
			(start 0.508 0.3048)
			(end -0.508 0.3048)
			(stroke
				(width 0.1)
				(type default)
			)
			(layer "B.Fab")
		)
		(fp_line
			(start -0.508 0.3048)
			(end -0.508 -0.3048)
			(stroke
				(width 0.1)
				(type default)
			)
			(layer "B.Fab")
		)
		(pad "1" smd rect
			(at 0.5334 0 270)
			(size 0.7112 0.6096)
			(layers "B.Cu" "B.Mask" "B.Paste")
			(net "XP3R3V")
		)
		(pad "2" smd rect
			(at -0.5334 0 270)
			(size 0.7112 0.6096)
			(layers "B.Cu" "B.Mask" "B.Paste")
			(net "SG")
		)
		(zone
			(layer "B.Cu")
			(hatch none 0.5)
			(connect_pads
				(clearance 0)
			)
			(min_thickness 0.25)
			(keepout
				(tracks allowed)
				(vias not_allowed)
				(pads allowed)
				(copperpour not_allowed)
				(footprints allowed)
			)
			(placement
				(enabled no)
				(sheetname "")
			)
			(fill
				(thermal_gap 0.5)
				(thermal_bridge_width 0.5)
				(island_removal_mode 0)
			)
			(polygon
				(pts
					(xy 95.4532 -19.9898) (xy 96.0628 -19.9898) (xy 96.0628 -20.1422) (xy 95.4532 -20.1422)
				)
			)
		)
	)
)
